(kicad_pcb
	(version 20260206)
	(generator "pcbnew")
	(generator_version "10.0")
	(general
		(thickness 1.6)
		(legacy_teardrops no)
	)
	(paper "A4")
	(title_block
		(title "03242023_DA0F0TMBIJ0_F0T_Motherboard_J_brd_V01_OCP.brd")
		(comment 1 "Grand Teton / footprint 3553 of 6105 (J6), pads 1-112 of 291")
	)
	(layers
		(0 "F.Cu" signal "TOP")
		(4 "In1.Cu" signal "GND")
		(6 "In2.Cu" signal "IN1")
		(8 "In3.Cu" signal "GND1")
		(10 "In4.Cu" signal "IN2")
		(12 "In5.Cu" signal "GND2")
		(14 "In6.Cu" signal "IN3")
		(16 "In7.Cu" signal "GND3")
		(18 "In8.Cu" signal "VCC")
		(20 "In9.Cu" signal "VCC1")
		(22 "In10.Cu" signal "GND4")
		(24 "In11.Cu" signal "IN4")
		(26 "In12.Cu" signal "GND5")
		(28 "In13.Cu" signal "IN5")
		(30 "In14.Cu" signal "GND6")
		(32 "In15.Cu" signal "IN6")
		(34 "In16.Cu" signal "GND7")
		(2 "B.Cu" signal "BOTTOM")
		(9 "F.Adhes" user "F.Adhesive")
		(11 "B.Adhes" user "B.Adhesive")
		(13 "F.Paste" user "Package Geometry/Pastemask Top")
		(15 "B.Paste" user "Package Geometry/Pastemask Bottom")
		(5 "F.SilkS" user "Ref Des/Silkscreen Top")
		(7 "B.SilkS" user "Ref Des/Silkscreen Bottom")
		(1 "F.Mask" user "Board Geometry/Soldermask Top")
		(3 "B.Mask" user "Board Geometry/Soldermask Bottom")
		(17 "Dwgs.User" user "User.Drawings")
		(19 "Cmts.User" user "User.Comments")
		(21 "Eco1.User" user "User.Eco1")
		(23 "Eco2.User" user "User.Eco2")
		(25 "Edge.Cuts" user "Board Geometry/Outline")
		(27 "Margin" user)
		(31 "F.CrtYd" user "Package Geometry/Place Bound Top")
		(29 "B.CrtYd" user "Package Geometry/Place Bound Bottom")
		(35 "F.Fab" user "Ref Des/Assembly Top")
		(33 "B.Fab" user "Ref Des/Assembly Bottom")
	)
	(footprint ""
		(layer "F.Cu")
		(at 280.761948 -258.091686)
		(property "Reference" "J6"
			(at -3.683 -81.702148 0)
			(unlocked yes)
			(layer "F.SilkS")
			(effects
				(font
					(size 0.7874 0.5842)
					(thickness 0.1524)
				)
				(justify left)
			)
		)
		(property "Value" ""
			(at 0 0 0)
			(layer "F.Fab")
			(effects
				(font
					(size 1.27 1.27)
				)
			)
		)
		(duplicate_pad_numbers_are_jumpers no)
		(pad "1" smd rect
			(at -2.050034 -63.324994 270)
			(size 0.519938 1.4986)
			(layers "F.Cu" "F.Mask" "F.Paste")
			(net "P12V_S3_AUX_CPU0_NVDIMM")
		)
		(pad "2" smd rect
			(at -2.050034 -62.47511 270)
			(size 0.519938 1.4986)
			(layers "F.Cu" "F.Mask" "F.Paste")
			(net "TP_CHC_CPU0_DIMM2_FRU_0")
		)
		(pad "3" smd rect
			(at -2.050034 -61.624972 270)
			(size 0.519938 1.4986)
			(layers "F.Cu" "F.Mask" "F.Paste")
			(net "P3V3_AUX")
		)
		(pad "4" smd rect
			(at -2.050034 -60.775088 270)
			(size 0.519938 1.4986)
			(layers "F.Cu" "F.Mask" "F.Paste")
			(net "I3C_SPD_DDRABCD_CPU0_LVC1_SCL_5")
		)
		(pad "5" smd rect
			(at -2.050034 -59.92495 270)
			(size 0.519938 1.4986)
			(layers "F.Cu" "F.Mask" "F.Paste")
			(net "I3C_SPD_DDRABCD_CPU0_LVC1_SDA")
		)
		(pad "6" smd rect
			(at -2.050034 -59.075066 270)
			(size 0.519938 1.4986)
			(layers "F.Cu" "F.Mask" "F.Paste")
			(net "GND")
		)
		(pad "7" smd rect
			(at -2.050034 -58.224928 270)
			(size 0.519938 1.4986)
			(layers "F.Cu" "F.Mask" "F.Paste")
			(net "M_C_CPU0_SA_DQ<0>")
		)
		(pad "8" smd rect
			(at -2.050034 -57.375044 270)
			(size 0.519938 1.4986)
			(layers "F.Cu" "F.Mask" "F.Paste")
			(net "GND")
		)
		(pad "9" smd rect
			(at -2.050034 -56.524906 270)
			(size 0.519938 1.4986)
			(layers "F.Cu" "F.Mask" "F.Paste")
			(net "M_C_CPU0_SA_DQ<1>")
		)
		(pad "10" smd rect
			(at -2.050034 -55.675022 270)
			(size 0.519938 1.4986)
			(layers "F.Cu" "F.Mask" "F.Paste")
			(net "GND")
		)
		(pad "11" smd rect
			(at -2.050034 -54.824884 270)
			(size 0.519938 1.4986)
			(layers "F.Cu" "F.Mask" "F.Paste")
			(net "M_C_CPU0_SA_DQS_DP<0>")
		)
		(pad "12" smd rect
			(at -2.050034 -53.975 270)
			(size 0.519938 1.4986)
			(layers "F.Cu" "F.Mask" "F.Paste")
			(net "M_C_CPU0_SA_DQS_DN<0>")
		)
		(pad "13" smd rect
			(at -2.050034 -53.125116 270)
			(size 0.519938 1.4986)
			(layers "F.Cu" "F.Mask" "F.Paste")
			(net "GND")
		)
		(pad "14" smd rect
			(at -2.050034 -52.274978 270)
			(size 0.519938 1.4986)
			(layers "F.Cu" "F.Mask" "F.Paste")
			(net "M_C_CPU0_SA_DQ<4>")
		)
		(pad "15" smd rect
			(at -2.050034 -51.425094 270)
			(size 0.519938 1.4986)
			(layers "F.Cu" "F.Mask" "F.Paste")
			(net "GND")
		)
		(pad "16" smd rect
			(at -2.050034 -50.574956 270)
			(size 0.519938 1.4986)
			(layers "F.Cu" "F.Mask" "F.Paste")
			(net "M_C_CPU0_SA_DQ<5>")
		)
		(pad "17" smd rect
			(at -2.050034 -49.725072 270)
			(size 0.519938 1.4986)
			(layers "F.Cu" "F.Mask" "F.Paste")
			(net "GND")
		)
		(pad "18" smd rect
			(at -2.050034 -48.874934 270)
			(size 0.519938 1.4986)
			(layers "F.Cu" "F.Mask" "F.Paste")
			(net "M_C_CPU0_SA_DQ<8>")
		)
		(pad "19" smd rect
			(at -2.050034 -48.02505 270)
			(size 0.519938 1.4986)
			(layers "F.Cu" "F.Mask" "F.Paste")
			(net "GND")
		)
		(pad "20" smd rect
			(at -2.050034 -47.174912 270)
			(size 0.519938 1.4986)
			(layers "F.Cu" "F.Mask" "F.Paste")
			(net "M_C_CPU0_SA_DQ<9>")
		)
		(pad "21" smd rect
			(at -2.050034 -46.325028 270)
			(size 0.519938 1.4986)
			(layers "F.Cu" "F.Mask" "F.Paste")
			(net "GND")
		)
		(pad "22" smd rect
			(at -2.050034 -45.47489 270)
			(size 0.519938 1.4986)
			(layers "F.Cu" "F.Mask" "F.Paste")
			(net "M_C_CPU0_SA_DQS_DP<1>")
		)
		(pad "23" smd rect
			(at -2.050034 -44.625006 270)
			(size 0.519938 1.4986)
			(layers "F.Cu" "F.Mask" "F.Paste")
			(net "M_C_CPU0_SA_DQS_DN<1>")
		)
		(pad "24" smd rect
			(at -2.050034 -43.775122 270)
			(size 0.519938 1.4986)
			(layers "F.Cu" "F.Mask" "F.Paste")
			(net "GND")
		)
		(pad "25" smd rect
			(at -2.050034 -42.924984 270)
			(size 0.519938 1.4986)
			(layers "F.Cu" "F.Mask" "F.Paste")
			(net "M_C_CPU0_SA_DQ<12>")
		)
		(pad "26" smd rect
			(at -2.050034 -42.0751 270)
			(size 0.519938 1.4986)
			(layers "F.Cu" "F.Mask" "F.Paste")
			(net "GND")
		)
		(pad "27" smd rect
			(at -2.050034 -41.224962 270)
			(size 0.519938 1.4986)
			(layers "F.Cu" "F.Mask" "F.Paste")
			(net "M_C_CPU0_SA_DQ<13>")
		)
		(pad "28" smd rect
			(at -2.050034 -40.375078 270)
			(size 0.519938 1.4986)
			(layers "F.Cu" "F.Mask" "F.Paste")
			(net "GND")
		)
		(pad "29" smd rect
			(at -2.050034 -39.52494 270)
			(size 0.519938 1.4986)
			(layers "F.Cu" "F.Mask" "F.Paste")
			(net "M_C_CPU0_SA_DQ<16>")
		)
		(pad "30" smd rect
			(at -2.050034 -38.675056 270)
			(size 0.519938 1.4986)
			(layers "F.Cu" "F.Mask" "F.Paste")
			(net "GND")
		)
		(pad "31" smd rect
			(at -2.050034 -37.824918 270)
			(size 0.519938 1.4986)
			(layers "F.Cu" "F.Mask" "F.Paste")
			(net "M_C_CPU0_SA_DQ<17>")
		)
		(pad "32" smd rect
			(at -2.050034 -36.975034 270)
			(size 0.519938 1.4986)
			(layers "F.Cu" "F.Mask" "F.Paste")
			(net "GND")
		)
		(pad "33" smd rect
			(at -2.050034 -36.124896 270)
			(size 0.519938 1.4986)
			(layers "F.Cu" "F.Mask" "F.Paste")
			(net "M_C_CPU0_SA_DQS_DP<2>")
		)
		(pad "34" smd rect
			(at -2.050034 -35.275012 270)
			(size 0.519938 1.4986)
			(layers "F.Cu" "F.Mask" "F.Paste")
			(net "M_C_CPU0_SA_DQS_DN<2>")
		)
		(pad "35" smd rect
			(at -2.050034 -34.425128 270)
			(size 0.519938 1.4986)
			(layers "F.Cu" "F.Mask" "F.Paste")
			(net "GND")
		)
		(pad "36" smd rect
			(at -2.050034 -33.57499 270)
			(size 0.519938 1.4986)
			(layers "F.Cu" "F.Mask" "F.Paste")
			(net "M_C_CPU0_SA_DQ<20>")
		)
		(pad "37" smd rect
			(at -2.050034 -32.725106 270)
			(size 0.519938 1.4986)
			(layers "F.Cu" "F.Mask" "F.Paste")
			(net "GND")
		)
		(pad "38" smd rect
			(at -2.050034 -31.874968 270)
			(size 0.519938 1.4986)
			(layers "F.Cu" "F.Mask" "F.Paste")
			(net "M_C_CPU0_SA_DQ<21>")
		)
		(pad "39" smd rect
			(at -2.050034 -31.025084 270)
			(size 0.519938 1.4986)
			(layers "F.Cu" "F.Mask" "F.Paste")
			(net "GND")
		)
		(pad "40" smd rect
			(at -2.050034 -30.174946 270)
			(size 0.519938 1.4986)
			(layers "F.Cu" "F.Mask" "F.Paste")
			(net "M_C_CPU0_SA_DQ<24>")
		)
		(pad "41" smd rect
			(at -2.050034 -29.325062 270)
			(size 0.519938 1.4986)
			(layers "F.Cu" "F.Mask" "F.Paste")
			(net "GND")
		)
		(pad "42" smd rect
			(at -2.050034 -28.474924 270)
			(size 0.519938 1.4986)
			(layers "F.Cu" "F.Mask" "F.Paste")
			(net "M_C_CPU0_SA_DQ<25>")
		)
		(pad "43" smd rect
			(at -2.050034 -27.62504 270)
			(size 0.519938 1.4986)
			(layers "F.Cu" "F.Mask" "F.Paste")
			(net "GND")
		)
		(pad "44" smd rect
			(at -2.050034 -26.774902 270)
			(size 0.519938 1.4986)
			(layers "F.Cu" "F.Mask" "F.Paste")
			(net "M_C_CPU0_SA_DQS_DP<3>")
		)
		(pad "45" smd rect
			(at -2.050034 -25.925018 270)
			(size 0.519938 1.4986)
			(layers "F.Cu" "F.Mask" "F.Paste")
			(net "M_C_CPU0_SA_DQS_DN<3>")
		)
		(pad "46" smd rect
			(at -2.050034 -25.07488 270)
			(size 0.519938 1.4986)
			(layers "F.Cu" "F.Mask" "F.Paste")
			(net "GND")
		)
		(pad "47" smd rect
			(at -2.050034 -24.224996 270)
			(size 0.519938 1.4986)
			(layers "F.Cu" "F.Mask" "F.Paste")
			(net "M_C_CPU0_SA_DQ<28>")
		)
		(pad "48" smd rect
			(at -2.050034 -23.375112 270)
			(size 0.519938 1.4986)
			(layers "F.Cu" "F.Mask" "F.Paste")
			(net "GND")
		)
		(pad "49" smd rect
			(at -2.050034 -22.524974 270)
			(size 0.519938 1.4986)
			(layers "F.Cu" "F.Mask" "F.Paste")
			(net "M_C_CPU0_SA_DQ<29>")
		)
		(pad "50" smd rect
			(at -2.050034 -21.67509 270)
			(size 0.519938 1.4986)
			(layers "F.Cu" "F.Mask" "F.Paste")
			(net "GND")
		)
		(pad "51" smd rect
			(at -2.050034 -20.824952 270)
			(size 0.519938 1.4986)
			(layers "F.Cu" "F.Mask" "F.Paste")
			(net "M_C_CPU0_SA_CB<0>")
		)
		(pad "52" smd rect
			(at -2.050034 -19.975068 270)
			(size 0.519938 1.4986)
			(layers "F.Cu" "F.Mask" "F.Paste")
			(net "GND")
		)
		(pad "53" smd rect
			(at -2.050034 -19.12493 270)
			(size 0.519938 1.4986)
			(layers "F.Cu" "F.Mask" "F.Paste")
			(net "M_C_CPU0_SA_CB<1>")
		)
		(pad "54" smd rect
			(at -2.050034 -18.275046 270)
			(size 0.519938 1.4986)
			(layers "F.Cu" "F.Mask" "F.Paste")
			(net "GND")
		)
		(pad "55" smd rect
			(at -2.050034 -17.424908 270)
			(size 0.519938 1.4986)
			(layers "F.Cu" "F.Mask" "F.Paste")
			(net "M_C_CPU0_SA_DQS_DP<4>")
		)
		(pad "56" smd rect
			(at -2.050034 -16.575024 270)
			(size 0.519938 1.4986)
			(layers "F.Cu" "F.Mask" "F.Paste")
			(net "M_C_CPU0_SA_DQS_DN<4>")
		)
		(pad "57" smd rect
			(at -2.050034 -15.724886 270)
			(size 0.519938 1.4986)
			(layers "F.Cu" "F.Mask" "F.Paste")
			(net "GND")
		)
		(pad "58" smd rect
			(at -2.050034 -14.875002 270)
			(size 0.519938 1.4986)
			(layers "F.Cu" "F.Mask" "F.Paste")
			(net "M_C_CPU0_SA_CB<4>")
		)
		(pad "59" smd rect
			(at -2.050034 -14.025118 270)
			(size 0.519938 1.4986)
			(layers "F.Cu" "F.Mask" "F.Paste")
			(net "GND")
		)
		(pad "60" smd rect
			(at -2.050034 -13.17498 270)
			(size 0.519938 1.4986)
			(layers "F.Cu" "F.Mask" "F.Paste")
			(net "M_C_CPU0_SA_CB<5>")
		)
		(pad "61" smd rect
			(at -2.050034 -12.325096 270)
			(size 0.519938 1.4986)
			(layers "F.Cu" "F.Mask" "F.Paste")
			(net "GND")
		)
		(pad "62" smd rect
			(at -2.050034 -11.474958 270)
			(size 0.519938 1.4986)
			(layers "F.Cu" "F.Mask" "F.Paste")
			(net "M_C_CPU0_ALERT_N")
		)
		(pad "63" smd rect
			(at -2.050034 -10.625074 270)
			(size 0.519938 1.4986)
			(layers "F.Cu" "F.Mask" "F.Paste")
			(net "GND")
		)
		(pad "64" smd rect
			(at -2.050034 -9.774936 270)
			(size 0.519938 1.4986)
			(layers "F.Cu" "F.Mask" "F.Paste")
			(net "M_C_CPU0_SA_CS_N<2>")
		)
		(pad "65" smd rect
			(at -2.050034 -8.925052 270)
			(size 0.519938 1.4986)
			(layers "F.Cu" "F.Mask" "F.Paste")
			(net "GND")
		)
		(pad "66" smd rect
			(at -2.050034 -8.074914 270)
			(size 0.519938 1.4986)
			(layers "F.Cu" "F.Mask" "F.Paste")
			(net "M_C_CPU0_SA_CA<0>")
		)
		(pad "67" smd rect
			(at -2.050034 -7.22503 270)
			(size 0.519938 1.4986)
			(layers "F.Cu" "F.Mask" "F.Paste")
			(net "GND")
		)
		(pad "68" smd rect
			(at -2.050034 -6.374892 270)
			(size 0.519938 1.4986)
			(layers "F.Cu" "F.Mask" "F.Paste")
			(net "M_C_CPU0_SA_CA<2>")
		)
		(pad "69" smd rect
			(at -2.050034 -5.525008 270)
			(size 0.519938 1.4986)
			(layers "F.Cu" "F.Mask" "F.Paste")
			(net "GND")
		)
		(pad "70" smd rect
			(at -2.050034 -4.675124 270)
			(size 0.519938 1.4986)
			(layers "F.Cu" "F.Mask" "F.Paste")
			(net "M_C_CPU0_SA_CA<4>")
		)
		(pad "71" smd rect
			(at -2.050034 -3.824986 270)
			(size 0.519938 1.4986)
			(layers "F.Cu" "F.Mask" "F.Paste")
			(net "GND")
		)
		(pad "72" smd rect
			(at -2.050034 -2.975102 270)
			(size 0.519938 1.4986)
			(layers "F.Cu" "F.Mask" "F.Paste")
			(net "M_C_CPU0_SA_CA<6>")
		)
		(pad "73" smd rect
			(at -2.050034 -2.124964 270)
			(size 0.519938 1.4986)
			(layers "F.Cu" "F.Mask" "F.Paste")
			(net "GND")
		)
		(pad "74" smd rect
			(at -2.050034 -1.27508 270)
			(size 0.519938 1.4986)
			(layers "F.Cu" "F.Mask" "F.Paste")
			(net "M_C_CPU0_SA_PAR")
		)
		(pad "75" smd rect
			(at -2.050034 -0.424942 270)
			(size 0.519938 1.4986)
			(layers "F.Cu" "F.Mask" "F.Paste")
			(net "GND")
		)
		(pad "76" smd rect
			(at -2.050034 5.525008 270)
			(size 0.519938 1.4986)
			(layers "F.Cu" "F.Mask" "F.Paste")
			(net "M_C_CPU0_SB_CA<0>")
		)
		(pad "77" smd rect
			(at -2.050034 6.374892 270)
			(size 0.519938 1.4986)
			(layers "F.Cu" "F.Mask" "F.Paste")
			(net "GND")
		)
		(pad "78" smd rect
			(at -2.050034 7.22503 270)
			(size 0.519938 1.4986)
			(layers "F.Cu" "F.Mask" "F.Paste")
			(net "M_C_CPU0_SB_CA<2>")
		)
		(pad "79" smd rect
			(at -2.050034 8.074914 270)
			(size 0.519938 1.4986)
			(layers "F.Cu" "F.Mask" "F.Paste")
			(net "GND")
		)
		(pad "80" smd rect
			(at -2.050034 8.925052 270)
			(size 0.519938 1.4986)
			(layers "F.Cu" "F.Mask" "F.Paste")
			(net "M_C_CPU0_SB_CA<4>")
		)
		(pad "81" smd rect
			(at -2.050034 9.774936 270)
			(size 0.519938 1.4986)
			(layers "F.Cu" "F.Mask" "F.Paste")
			(net "GND")
		)
		(pad "82" smd rect
			(at -2.050034 10.625074 270)
			(size 0.519938 1.4986)
			(layers "F.Cu" "F.Mask" "F.Paste")
			(net "M_C_CPU0_SB_CA<6>")
		)
		(pad "83" smd rect
			(at -2.050034 11.474958 270)
			(size 0.519938 1.4986)
			(layers "F.Cu" "F.Mask" "F.Paste")
			(net "GND")
		)
		(pad "84" smd rect
			(at -2.050034 12.325096 270)
			(size 0.519938 1.4986)
			(layers "F.Cu" "F.Mask" "F.Paste")
			(net "M_C_CPU0_SB_CS_N<2>")
		)
		(pad "85" smd rect
			(at -2.050034 13.17498 270)
			(size 0.519938 1.4986)
			(layers "F.Cu" "F.Mask" "F.Paste")
			(net "GND")
		)
		(pad "86" smd rect
			(at -2.050034 14.025118 270)
			(size 0.519938 1.4986)
			(layers "F.Cu" "F.Mask" "F.Paste")
			(net "M_C_CPU0_SA_RSP<1>")
		)
		(pad "87" smd rect
			(at -2.050034 14.875002 270)
			(size 0.519938 1.4986)
			(layers "F.Cu" "F.Mask" "F.Paste")
			(net "M_C_CPU0_SB_RSP<1>")
		)
		(pad "88" smd rect
			(at -2.050034 15.724886 270)
			(size 0.519938 1.4986)
			(layers "F.Cu" "F.Mask" "F.Paste")
			(net "GND")
		)
		(pad "89" smd rect
			(at -2.050034 16.575024 270)
			(size 0.519938 1.4986)
			(layers "F.Cu" "F.Mask" "F.Paste")
			(net "M_C_CPU0_SB_CB<4>")
		)
		(pad "90" smd rect
			(at -2.050034 17.424908 270)
			(size 0.519938 1.4986)
			(layers "F.Cu" "F.Mask" "F.Paste")
			(net "GND")
		)
		(pad "91" smd rect
			(at -2.050034 18.275046 270)
			(size 0.519938 1.4986)
			(layers "F.Cu" "F.Mask" "F.Paste")
			(net "M_C_CPU0_SB_CB<5>")
		)
		(pad "92" smd rect
			(at -2.050034 19.12493 270)
			(size 0.519938 1.4986)
			(layers "F.Cu" "F.Mask" "F.Paste")
			(net "GND")
		)
		(pad "93" smd rect
			(at -2.050034 19.975068 270)
			(size 0.519938 1.4986)
			(layers "F.Cu" "F.Mask" "F.Paste")
			(net "M_C_CPU0_SB_DQS_DP<9>")
		)
		(pad "94" smd rect
			(at -2.050034 20.824952 270)
			(size 0.519938 1.4986)
			(layers "F.Cu" "F.Mask" "F.Paste")
			(net "M_C_CPU0_SB_DQS_DN<9>")
		)
		(pad "95" smd rect
			(at -2.050034 21.67509 270)
			(size 0.519938 1.4986)
			(layers "F.Cu" "F.Mask" "F.Paste")
			(net "GND")
		)
		(pad "96" smd rect
			(at -2.050034 22.524974 270)
			(size 0.519938 1.4986)
			(layers "F.Cu" "F.Mask" "F.Paste")
			(net "M_C_CPU0_SB_CB<0>")
		)
		(pad "97" smd rect
			(at -2.050034 23.375112 270)
			(size 0.519938 1.4986)
			(layers "F.Cu" "F.Mask" "F.Paste")
			(net "GND")
		)
		(pad "98" smd rect
			(at -2.050034 24.224996 270)
			(size 0.519938 1.4986)
			(layers "F.Cu" "F.Mask" "F.Paste")
			(net "M_C_CPU0_SB_CB<1>")
		)
		(pad "99" smd rect
			(at -2.050034 25.07488 270)
			(size 0.519938 1.4986)
			(layers "F.Cu" "F.Mask" "F.Paste")
			(net "GND")
		)
		(pad "100" smd rect
			(at -2.050034 25.925018 270)
			(size 0.519938 1.4986)
			(layers "F.Cu" "F.Mask" "F.Paste")
			(net "M_C_CPU0_SB_DQ<0>")
		)
		(pad "101" smd rect
			(at -2.050034 26.774902 270)
			(size 0.519938 1.4986)
			(layers "F.Cu" "F.Mask" "F.Paste")
			(net "GND")
		)
		(pad "102" smd rect
			(at -2.050034 27.62504 270)
			(size 0.519938 1.4986)
			(layers "F.Cu" "F.Mask" "F.Paste")
			(net "M_C_CPU0_SB_DQ<1>")
		)
		(pad "103" smd rect
			(at -2.050034 28.474924 270)
			(size 0.519938 1.4986)
			(layers "F.Cu" "F.Mask" "F.Paste")
			(net "GND")
		)
		(pad "104" smd rect
			(at -2.050034 29.325062 270)
			(size 0.519938 1.4986)
			(layers "F.Cu" "F.Mask" "F.Paste")
			(net "M_C_CPU0_SB_DQS_DP<0>")
		)
		(pad "105" smd rect
			(at -2.050034 30.174946 270)
			(size 0.519938 1.4986)
			(layers "F.Cu" "F.Mask" "F.Paste")
			(net "M_C_CPU0_SB_DQS_DN<0>")
		)
		(pad "106" smd rect
			(at -2.050034 31.025084 270)
			(size 0.519938 1.4986)
			(layers "F.Cu" "F.Mask" "F.Paste")
			(net "GND")
		)
		(pad "107" smd rect
			(at -2.050034 31.874968 270)
			(size 0.519938 1.4986)
			(layers "F.Cu" "F.Mask" "F.Paste")
			(net "M_C_CPU0_SB_DQ<4>")
		)
		(pad "108" smd rect
			(at -2.050034 32.725106 270)
			(size 0.519938 1.4986)
			(layers "F.Cu" "F.Mask" "F.Paste")
			(net "GND")
		)
		(pad "109" smd rect
			(at -2.050034 33.57499 270)
			(size 0.519938 1.4986)
			(layers "F.Cu" "F.Mask" "F.Paste")
			(net "M_C_CPU0_SB_DQ<5>")
		)
		(pad "110" smd rect
			(at -2.050034 34.425128 270)
			(size 0.519938 1.4986)
			(layers "F.Cu" "F.Mask" "F.Paste")
			(net "GND")
		)
		(pad "111" smd rect
			(at -2.050034 35.275012 270)
			(size 0.519938 1.4986)
			(layers "F.Cu" "F.Mask" "F.Paste")
			(net "M_C_CPU0_SB_DQ<8>")
		)
		(pad "112" smd rect
			(at -2.050034 36.124896 270)
			(size 0.519938 1.4986)
			(layers "F.Cu" "F.Mask" "F.Paste")
			(net "GND")
		)
	)
)
